# BASEBOARD_FAB2 (Tioga Pass) — schematic netlist excerpt (pin names and nets, part order shuffled) for the footprints in the layout excerpt that follows; sources: Cadence DE-HDL packaged netlist, KiCad conversion of Wiwynn_Tioga_Pass_MB.brd

EU1C2  PXE1610B  IC  pkg QFN  page 206
  BPWM1  = VR_PVSA_CPU1_PWM
  APWM6  = NC
  APWM5  = VR_PVCCIN_CPU1_PWM5
  APWM4  = VR_PVCCIN_CPU1_PWM4
  APWM3  = VR_PVCCIN_CPU1_PWM3
  APWM2  = VR_PVCCIN_CPU1_PWM2
  APWM1  = VR_PVCCIN_CPU1_PWM1
  SDA  = SMB_VR_STBY_LVC3_SDA
  SCL  = SMB_VR_STBY_LVC3_SCL
  RESET_N  = NC
  AVRRDY  = VR_VRRDY_PVCCIN_CPU1
  AVREN  = VR_PVCCIN_CPU1_VREN
  VRHOT_N  = IRQ_PVCCIN_CPU1_VRHOT_LVC3_R_N
  PINALRT_N  = FM_PVCCIN_CPU1_PWR_IN_ALERT_N
  MP0  = PWRGD_PVSA_CPU1_R
  MP1  = NC
  VCLK  = SVID_VCLK_PVCCIN_CPU1
  VDIO  = SVID_VDIO_PVCCIN_CPU1
  VALRT_N  = SVID_VALERT_VCCIN_CPU1
  MP2  = PU_VR_PVCCIN_CPU1_FLT1_SMBALT_N
  AVSEN  = VSENSE_PVCCIN_CPU1_AVSP
  AVREF  = VSENSE_PVCCIN_CPU1_N
  AIREF1  = VR_PVCCIN_CPU1_AIREF1
  AISEN1  = ISENSE_PVCCIN_CPU1_PH1_IMON
  AIREF2  = VR_PVCCIN_CPU1_AIREF2
  AISEN2  = ISENSE_PVCCIN_CPU1_PH2_IMON
  AIREF3  = VR_PVCCIN_CPU1_AIREF3
  AISEN3  = ISENSE_PVCCIN_CPU1_PH3_IMON
  AIREF4  = VR_PVCCIN_CPU1_AIREF4
  AISEN4  = ISENSE_PVCCIN_CPU1_PH4_IMON
  AIREF5  = VR_PVCCIN_CPU1_AIREF5
  AISEN5  = ISENSE_PVCCIN_CPU1_PH5_IMON
  AIREF6  = NC
  AISEN6  = NC
  BVSEN  = VSENSE_PVSA_CPU1_BVSP
  BVREF  = VSENSE_PVSA_CPU1_N
  BIREF1  = VR_PVSA_CPU1_BIREF1
  BISEN1  = ISENSE_PVSA_CPU1_IMON
  MP3  = PU_VR_PVCCIN_CPU1_IMON
  MP4  = NC
  XADDR2  = VR_PVCCIN_CPU1_XADDR2
  BTSEN  = A_TSENSE_PVSA_CPU1
  ATSEN  = A_TSENSE_PVCCIN_CPU1
  XADDR1  = VR_PVCCIN_CPU1_XADDR1
  VINSEN  = VR_PVCCIN_CPU1_AVINSEN
  IINSEN  = NC
  VDD  = VR_PVCCIN_CPU1_VDD
  VD12  = VR_PVCCIN_CPU1_VD12
  THPAD  = GND

(kicad_pcb
	(version 20260206)
	(generator "pcbnew")
	(generator_version "10.0")
	(general
		(thickness 1.6)
		(legacy_teardrops no)
	)
	(paper "A4")
	(title_block
		(title "Wiwynn_Tioga_Pass_MB.brd")
		(comment 1 "Tioga Pass / footprint 241 of 4770 (EU1C2), pads 35-49 of 49")
	)
	(layers
		(0 "F.Cu" signal "TOP")
		(4 "In1.Cu" signal "L2GND")
		(6 "In2.Cu" signal "L3")
		(8 "In3.Cu" signal "L4GND")
		(10 "In4.Cu" signal "L5")
		(12 "In5.Cu" signal "L6GND")
		(14 "In6.Cu" signal "L7VCC")
		(16 "In7.Cu" signal "L8VCC")
		(18 "In8.Cu" signal "L9GND")
		(20 "In9.Cu" signal "L10")
		(22 "In10.Cu" signal "L11GND")
		(24 "In11.Cu" signal "L12")
		(26 "In12.Cu" signal "L13GND")
		(2 "B.Cu" signal "BOTTOM")
		(9 "F.Adhes" user "F.Adhesive")
		(11 "B.Adhes" user "B.Adhesive")
		(13 "F.Paste" user "Package Geometry/Pastemask Top")
		(15 "B.Paste" user "Package Geometry/Pastemask Bottom")
		(5 "F.SilkS" user "Ref Des/Silkscreen Top")
		(7 "B.SilkS" user "Ref Des/Silkscreen Bottom")
		(1 "F.Mask" user "Board Geometry/Soldermask Top")
		(3 "B.Mask" user "Board Geometry/Soldermask Bottom")
		(17 "Dwgs.User" user "User.Drawings")
		(19 "Cmts.User" user "User.Comments")
		(21 "Eco1.User" user "User.Eco1")
		(23 "Eco2.User" user "User.Eco2")
		(25 "Edge.Cuts" user "Board Geometry/Outline")
		(27 "Margin" user)
		(31 "F.CrtYd" user "Package Geometry/Place Bound Top")
		(29 "B.CrtYd" user "Package Geometry/Place Bound Bottom")
		(35 "F.Fab" user "Ref Des/Assembly Top")
		(33 "B.Fab" user "Ref Des/Assembly Bottom")
	)
	(footprint ""
		(layer "F.Cu")
		(at 19.431 -92.456)
		(property "Reference" "EU1C2"
			(at -7.8232 -3.45313 0)
			(unlocked yes)
			(layer "F.SilkS")
			(effects
				(font
					(size 0.7874 0.5842)
					(thickness 0.1524)
				)
				(justify left)
			)
		)
		(property "Value" ""
			(at 0 0 0)
			(layer "F.Fab")
			(effects
				(font
					(size 1.27 1.27)
				)
			)
		)
		(duplicate_pad_numbers_are_jumpers no)
		(pad "35" smd custom
			(at 2.8956 -1.800098)
			(size 0.0508 0.0508)
			(layers "F.Cu" "F.Mask" "F.Paste")
			(net "VSENSE_PVSA_CPU1_BVSP")
			(options
				(clearance outline)
				(anchor circle)
			)
			(primitives
				(gr_poly
					(pts
						(arc
							(start -0.254 0.1016)
							(mid -0.3556 0)
							(end -0.254 -0.1016)
						)
						(xy 0.3556 -0.1016) (xy 0.3556 0.1016)
					)
					(width 0)
					(fill yes)
				)
			)
		)
		(pad "36" smd custom
			(at 2.8956 -2.199894)
			(size 0.0508 0.0508)
			(layers "F.Cu" "F.Mask" "F.Paste")
			(net "VSENSE_PVSA_CPU1_N")
			(options
				(clearance outline)
				(anchor circle)
			)
			(primitives
				(gr_poly
					(pts
						(arc
							(start -0.254 0.1016)
							(mid -0.3556 0)
							(end -0.254 -0.1016)
						)
						(xy 0.3556 -0.1016) (xy 0.3556 0.1016)
					)
					(width 0)
					(fill yes)
				)
			)
		)
		(pad "37" smd custom
			(at 2.199894 -2.8956)
			(size 0.0508 0.0508)
			(layers "F.Cu" "F.Mask" "F.Paste")
			(net "VR_PVSA_CPU1_BIREF1")
			(options
				(clearance outline)
				(anchor circle)
			)
			(primitives
				(gr_poly
					(pts
						(arc
							(start 0.1016 0.254)
							(mid 0 0.3556)
							(end -0.1016 0.254)
						)
						(xy -0.1016 -0.3556) (xy 0.1016 -0.3556)
					)
					(width 0)
					(fill yes)
				)
			)
		)
		(pad "38" smd custom
			(at 1.800098 -2.8956)
			(size 0.0508 0.0508)
			(layers "F.Cu" "F.Mask" "F.Paste")
			(net "ISENSE_PVSA_CPU1_IMON")
			(options
				(clearance outline)
				(anchor circle)
			)
			(primitives
				(gr_poly
					(pts
						(arc
							(start 0.1016 0.254)
							(mid 0 0.3556)
							(end -0.1016 0.254)
						)
						(xy -0.1016 -0.3556) (xy 0.1016 -0.3556)
					)
					(width 0)
					(fill yes)
				)
			)
		)
		(pad "39" smd custom
			(at 1.400048 -2.8956)
			(size 0.0508 0.0508)
			(layers "F.Cu" "F.Mask" "F.Paste")
			(net "PU_VR_PVCCIN_CPU1_IMON")
			(options
				(clearance outline)
				(anchor circle)
			)
			(primitives
				(gr_poly
					(pts
						(arc
							(start 0.1016 0.254)
							(mid 0 0.3556)
							(end -0.1016 0.254)
						)
						(xy -0.1016 -0.3556) (xy 0.1016 -0.3556)
					)
					(width 0)
					(fill yes)
				)
			)
		)
		(pad "40" smd custom
			(at 0.999998 -2.8956)
			(size 0.0508 0.0508)
			(layers "F.Cu" "F.Mask" "F.Paste")
			(net "Net_293")
			(options
				(clearance outline)
				(anchor circle)
			)
			(primitives
				(gr_poly
					(pts
						(arc
							(start 0.1016 0.254)
							(mid 0 0.3556)
							(end -0.1016 0.254)
						)
						(xy -0.1016 -0.3556) (xy 0.1016 -0.3556)
					)
					(width 0)
					(fill yes)
				)
			)
		)
		(pad "41" smd custom
			(at 0.599948 -2.8956)
			(size 0.0508 0.0508)
			(layers "F.Cu" "F.Mask" "F.Paste")
			(net "VR_PVCCIN_CPU1_XADDR2")
			(options
				(clearance outline)
				(anchor circle)
			)
			(primitives
				(gr_poly
					(pts
						(arc
							(start 0.1016 0.254)
							(mid 0 0.3556)
							(end -0.1016 0.254)
						)
						(xy -0.1016 -0.3556) (xy 0.1016 -0.3556)
					)
					(width 0)
					(fill yes)
				)
			)
		)
		(pad "42" smd custom
			(at 0.199898 -2.8956)
			(size 0.0508 0.0508)
			(layers "F.Cu" "F.Mask" "F.Paste")
			(net "A_TSENSE_PVSA_CPU1")
			(options
				(clearance outline)
				(anchor circle)
			)
			(primitives
				(gr_poly
					(pts
						(arc
							(start 0.1016 0.254)
							(mid 0 0.3556)
							(end -0.1016 0.254)
						)
						(xy -0.1016 -0.3556) (xy 0.1016 -0.3556)
					)
					(width 0)
					(fill yes)
				)
			)
		)
		(pad "43" smd custom
			(at -0.199898 -2.8956)
			(size 0.0508 0.0508)
			(layers "F.Cu" "F.Mask" "F.Paste")
			(net "A_TSENSE_PVCCIN_CPU1")
			(options
				(clearance outline)
				(anchor circle)
			)
			(primitives
				(gr_poly
					(pts
						(arc
							(start 0.1016 0.254)
							(mid 0 0.3556)
							(end -0.1016 0.254)
						)
						(xy -0.1016 -0.3556) (xy 0.1016 -0.3556)
					)
					(width 0)
					(fill yes)
				)
			)
		)
		(pad "44" smd custom
			(at -0.599948 -2.8956)
			(size 0.0508 0.0508)
			(layers "F.Cu" "F.Mask" "F.Paste")
			(net "VR_PVCCIN_CPU1_XADDR1")
			(options
				(clearance outline)
				(anchor circle)
			)
			(primitives
				(gr_poly
					(pts
						(arc
							(start 0.1016 0.254)
							(mid 0 0.3556)
							(end -0.1016 0.254)
						)
						(xy -0.1016 -0.3556) (xy 0.1016 -0.3556)
					)
					(width 0)
					(fill yes)
				)
			)
		)
		(pad "45" smd custom
			(at -0.999998 -2.8956)
			(size 0.0508 0.0508)
			(layers "F.Cu" "F.Mask" "F.Paste")
			(net "VR_PVCCIN_CPU1_AVINSEN")
			(options
				(clearance outline)
				(anchor circle)
			)
			(primitives
				(gr_poly
					(pts
						(arc
							(start 0.1016 0.254)
							(mid 0 0.3556)
							(end -0.1016 0.254)
						)
						(xy -0.1016 -0.3556) (xy 0.1016 -0.3556)
					)
					(width 0)
					(fill yes)
				)
			)
		)
		(pad "46" smd custom
			(at -1.400048 -2.8956)
			(size 0.0508 0.0508)
			(layers "F.Cu" "F.Mask" "F.Paste")
			(net "Net_218")
			(options
				(clearance outline)
				(anchor circle)
			)
			(primitives
				(gr_poly
					(pts
						(arc
							(start 0.1016 0.254)
							(mid 0 0.3556)
							(end -0.1016 0.254)
						)
						(xy -0.1016 -0.3556) (xy 0.1016 -0.3556)
					)
					(width 0)
					(fill yes)
				)
			)
		)
		(pad "47" smd custom
			(at -1.800098 -2.8956)
			(size 0.0508 0.0508)
			(layers "F.Cu" "F.Mask" "F.Paste")
			(net "VR_PVCCIN_CPU1_VDD")
			(options
				(clearance outline)
				(anchor circle)
			)
			(primitives
				(gr_poly
					(pts
						(arc
							(start 0.1016 0.254)
							(mid 0 0.3556)
							(end -0.1016 0.254)
						)
						(xy -0.1016 -0.3556) (xy 0.1016 -0.3556)
					)
					(width 0)
					(fill yes)
				)
			)
		)
		(pad "48" smd custom
			(at -2.199894 -2.8956)
			(size 0.0508 0.0508)
			(layers "F.Cu" "F.Mask" "F.Paste")
			(net "VR_PVCCIN_CPU1_VD12")
			(options
				(clearance outline)
				(anchor circle)
			)
			(primitives
				(gr_poly
					(pts
						(arc
							(start 0.1016 0.254)
							(mid 0 0.3556)
							(end -0.1016 0.254)
						)
						(xy -0.1016 -0.3556) (xy 0.1016 -0.3556)
					)
					(width 0)
					(fill yes)
				)
			)
		)
		(pad "49" smd rect
			(at 0 0)
			(size 3.6068 3.6068)
			(layers "F.Cu" "F.Mask" "F.Paste")
			(net "GND")
		)
	)
)
